(kicad_pcb
	(version 20241229)
	(generator "pcbnew")
	(generator_version "9.0")
	(general
		(thickness 1.62)
		(legacy_teardrops no)
	)
	(paper "A3")
	(title_block
		(title "COM Express 7 Baseboard")
		(date "2025-02-04")
		(rev "1.1.2")
		(company "Antmicro Ltd")
		(comment 1 "www.antmicro.com")
		(comment 9 "footprints 251-252 of 802")
	)
	(layers
		(0 "F.Cu" signal)
		(4 "In1.Cu" signal)
		(6 "In2.Cu" signal)
		(8 "In3.Cu" signal)
		(10 "In4.Cu" signal)
		(12 "In5.Cu" signal)
		(14 "In6.Cu" signal)
		(2 "B.Cu" signal)
		(9 "F.Adhes" user "F.Adhesive")
		(11 "B.Adhes" user "B.Adhesive")
		(13 "F.Paste" user)
		(15 "B.Paste" user)
		(5 "F.SilkS" user "F.Silkscreen")
		(7 "B.SilkS" user "B.Silkscreen")
		(1 "F.Mask" user)
		(3 "B.Mask" user)
		(17 "Dwgs.User" user "User.Drawings")
		(19 "Cmts.User" user "User.Comments")
		(21 "Eco1.User" user "User.Eco1")
		(23 "Eco2.User" user "User.Eco2")
		(25 "Edge.Cuts" user)
		(27 "Margin" user)
		(31 "F.CrtYd" user "F.Courtyard")
		(29 "B.CrtYd" user "B.Courtyard")
		(35 "F.Fab" user)
		(33 "B.Fab" user)
	)
	(footprint "antmicro-footprints:TP_SMD_0.75mm"
		(layer "F.Cu")
		(at 135.59 129.56)
		(property "Reference" "TP81"
			(at 0.46 -1.25 90)
			(layer "F.SilkS")
			(effects
				(font
					(size 0.7 0.7)
					(thickness 0.15)
				)
				(justify left bottom)
			)
		)
		(property "Value" "TP_0.75mm_SMD"
			(at 0 1.2 0)
			(layer "F.Fab")
			(effects
				(font
					(size 0.7 0.7)
					(thickness 0.15)
				)
				(justify left bottom)
			)
		)
		(property "Author" "Antmicro"
			(at 0 0 0)
			(layer "F.Fab")
			(hide yes)
			(effects
				(font
					(size 1 1)
					(thickness 0.15)
				)
			)
		)
		(property "License" "Apache-2.0"
			(at 0 0 0)
			(layer "F.Fab")
			(hide yes)
			(effects
				(font
					(size 1 1)
					(thickness 0.15)
				)
			)
		)
		(property "MPN" ""
			(at 0 0 0)
			(layer "F.Fab")
			(hide yes)
			(effects
				(font
					(size 1 1)
					(thickness 0.15)
				)
			)
		)
		(property "Manufacturer" ""
			(at 0 0 0)
			(layer "F.Fab")
			(hide yes)
			(effects
				(font
					(size 1 1)
					(thickness 0.15)
				)
			)
		)
		(property "Public" "False"
			(at 0 0 0)
			(layer "F.Fab")
			(hide yes)
			(effects
				(font
					(size 1 1)
					(thickness 0.15)
				)
			)
		)
		(sheetname "KR to SFI #2")
		(sheetfile "kr_sfi.kicad_sch")
		(attr exclude_from_pos_files exclude_from_bom)
		(fp_circle
			(center 0 0)
			(end 0.475 0)
			(stroke
				(width 0.05)
				(type default)
			)
			(fill no)
			(layer "F.CrtYd")
		)
		(pad "1" smd circle
			(at 0 0)
			(size 0.75 0.75)
			(layers "F.Cu" "F.Mask")
			(net 744 "/2xSFP+/KR to SFI #2/TMS")
			(pinfunction "1")
			(pintype "passive")
			(teardrops
				(best_length_ratio 0.4)
				(max_length 1)
				(best_width_ratio 0.9)
				(max_width 2)
				(curved_edges yes)
				(filter_ratio 0.9)
				(enabled yes)
				(allow_two_segments yes)
				(prefer_zone_connections yes)
			)
		)
	)
	(footprint "antmicro-footprints:R_0402_1005Metric"
		(layer "F.Cu")
		(at 209.38 128.82 180)
		(descr "Resistor SMD 0402")
		(tags "resistor SMD 0402")
		(property "Reference" "R193"
			(at 0.83 -0.39 0)
			(layer "F.SilkS")
			(effects
				(font
					(size 0.7 0.7)
					(thickness 0.15)
				)
				(justify right bottom)
			)
		)
		(property "Value" "R_0R_0402"
			(at -1.011843 1.772047 0)
			(layer "F.Fab")
			(effects
				(font
					(size 0.7 0.7)
					(thickness 0.15)
				)
				(justify right bottom)
			)
		)
		(property "Datasheet" "https://industrial.panasonic.com/cdbs/www-data/pdf/RDA0000/AOA0000C301.pdf"
			(at 0 0 180)
			(layer "F.Fab")
			(hide yes)
			(effects
				(font
					(size 1.27 1.27)
					(thickness 0.15)
				)
			)
		)
		(property "Author" "Antmicro"
			(at 418.76 257.64 0)
			(layer "F.Fab")
			(hide yes)
			(effects
				(font
					(size 1 1)
					(thickness 0.15)
				)
			)
		)
		(property "Current" "1A"
			(at 418.76 257.64 0)
			(layer "F.Fab")
			(hide yes)
			(effects
				(font
					(size 1 1)
					(thickness 0.15)
				)
			)
		)
		(property "License" "Apache-2.0"
			(at 418.76 257.64 0)
			(layer "F.Fab")
			(hide yes)
			(effects
				(font
					(size 1 1)
					(thickness 0.15)
				)
			)
		)
		(property "MPN" "ERJ2GE0R00X"
			(at 418.76 257.64 0)
			(layer "F.Fab")
			(hide yes)
			(effects
				(font
					(size 1 1)
					(thickness 0.15)
				)
			)
		)
		(property "Manufacturer" "Panasonic"
			(at 418.76 257.64 0)
			(layer "F.Fab")
			(hide yes)
			(effects
				(font
					(size 1 1)
					(thickness 0.15)
				)
			)
		)
		(property "Public" "False"
			(at 418.76 257.64 0)
			(layer "F.Fab")
			(hide yes)
			(effects
				(font
					(size 1 1)
					(thickness 0.15)
				)
			)
		)
		(property "Tolerance" ""
			(at 418.76 257.64 0)
			(layer "F.Fab")
			(hide yes)
			(effects
				(font
					(size 1 1)
					(thickness 0.15)
				)
			)
		)
		(property "Val" "0R"
			(at 418.76 257.64 0)
			(layer "F.Fab")
			(hide yes)
			(effects
				(font
					(size 1 1)
					(thickness 0.15)
				)
			)
		)
		(sheetname "PCIe misc")
		(sheetfile "pcie_misc.kicad_sch")
		(attr smd)
		(fp_rect
			(start -0.925 -0.47)
			(end 0.925 0.47)
			(stroke
				(width 0.05)
				(type default)
			)
			(fill no)
			(layer "F.CrtYd")
		)
		(fp_rect
			(start -0.5 -0.25)
			(end 0.5 0.25)
			(stroke
				(width 0.15)
				(type solid)
			)
			(fill no)
			(layer "F.Fab")
		)
		(pad "1" smd roundrect
			(at -0.48 0 180)
			(size 0.59 0.64)
			(layers "F.Cu" "F.Mask" "F.Paste")
			(roundrect_rratio 0.25)
			(net 612 "/PCIe misc/DIF0-")
			(pintype "passive")
			(teardrops
				(best_length_ratio 0.2)
				(max_length 1)
				(best_width_ratio 0.9)
				(max_width 2)
				(curved_edges yes)
				(filter_ratio 0.9)
				(enabled yes)
				(allow_two_segments yes)
				(prefer_zone_connections yes)
			)
		)
		(pad "2" smd roundrect
			(at 0.48 0 180)
			(size 0.59 0.64)
			(layers "F.Cu" "F.Mask" "F.Paste")
			(roundrect_rratio 0.25)
			(net 229 "/M.2 key M #1/PCIE_{REF}.CK-")
			(pintype "passive")
			(teardrops
				(best_length_ratio 0.2)
				(max_length 1)
				(best_width_ratio 0.9)
				(max_width 2)
				(curved_edges yes)
				(filter_ratio 0.9)
				(enabled yes)
				(allow_two_segments yes)
				(prefer_zone_connections yes)
			)
		)
	)
)
